# T6G (Grand Teton) — schematic netlist excerpt (pin names and nets, part order shuffled) for the footprints in the layout excerpt that follows; sources: Cadence DE-HDL packaged netlist, KiCad conversion of 04192023_DAF0TMB3IC0_F0TG_MB_C_brd_V02_OCP.brd

R1464  Q_RES  4.7K 5% EMPTY  pkg 0201LF  page 320 : A = P1V8_CPU1_RT_1D ; B = JTAG_TDI_RT_CPU1_P0
R612  Q_RES  0 5% CHIP  pkg 0201LF  page 287 : A = CLK_100M_RETIMER_CPU0_P1_R_DN ; B = CLK_100M_RETIMER_CPU0_P1_DN
PR106  Q_RES  8.87K 1% EMPTY  pkg 0402LF  page 206 : A = PVDDIO_P0_LSET3 ; B = GND

(kicad_pcb
	(version 20260206)
	(generator "pcbnew")
	(generator_version "10.0")
	(general
		(thickness 1.6)
		(legacy_teardrops no)
	)
	(paper "A4")
	(title_block
		(title "04192023_DAF0TMB3IC0_F0TG_MB_C_brd_V02_OCP.brd")
		(comment 1 "Grand Teton / footprints 1222-1224 of 8354")
	)
	(layers
		(0 "F.Cu" signal "TOP")
		(4 "In1.Cu" signal "GND")
		(6 "In2.Cu" signal "IN1")
		(8 "In3.Cu" signal "GND1")
		(10 "In4.Cu" signal "IN2")
		(12 "In5.Cu" signal "GND2")
		(14 "In6.Cu" signal "IN3")
		(16 "In7.Cu" signal "GND3")
		(18 "In8.Cu" signal "VCC")
		(20 "In9.Cu" signal "VCC1")
		(22 "In10.Cu" signal "GND4")
		(24 "In11.Cu" signal "IN4")
		(26 "In12.Cu" signal "GND5")
		(28 "In13.Cu" signal "IN5")
		(30 "In14.Cu" signal "GND6")
		(32 "In15.Cu" signal "IN6")
		(34 "In16.Cu" signal "GND7")
		(2 "B.Cu" signal "BOTTOM")
		(9 "F.Adhes" user "F.Adhesive")
		(11 "B.Adhes" user "B.Adhesive")
		(13 "F.Paste" user "Package Geometry/Pastemask Top")
		(15 "B.Paste" user "Package Geometry/Pastemask Bottom")
		(5 "F.SilkS" user "Ref Des/Silkscreen Top")
		(7 "B.SilkS" user "Ref Des/Silkscreen Bottom")
		(1 "F.Mask" user "Board Geometry/Soldermask Top")
		(3 "B.Mask" user "Board Geometry/Soldermask Bottom")
		(17 "Dwgs.User" user "User.Drawings")
		(19 "Cmts.User" user "User.Comments")
		(21 "Eco1.User" user "User.Eco1")
		(23 "Eco2.User" user "User.Eco2")
		(25 "Edge.Cuts" user "Board Geometry/Outline")
		(27 "Margin" user)
		(31 "F.CrtYd" user "Package Geometry/Place Bound Top")
		(29 "B.CrtYd" user "Package Geometry/Place Bound Bottom")
		(35 "F.Fab" user "Ref Des/Assembly Top")
		(33 "B.Fab" user "Ref Des/Assembly Bottom")
	)
	(footprint ""
		(layer "F.Cu")
		(at 331.055472 -395.333474)
		(property "Reference" "R612"
			(at 0 0 0)
			(layer "F.SilkS")
			(hide yes)
			(effects
				(font
					(size 1.27 1.27)
				)
			)
		)
		(property "Value" ""
			(at 0 0 0)
			(layer "F.Fab")
			(effects
				(font
					(size 1.27 1.27)
				)
			)
		)
		(duplicate_pad_numbers_are_jumpers no)
		(fp_line
			(start -0.32512 -0.175006)
			(end 0.32512 -0.175006)
			(stroke
				(width 0.1)
				(type default)
			)
			(layer "F.Fab")
		)
		(fp_line
			(start -0.32512 0.175006)
			(end -0.32512 -0.175006)
			(stroke
				(width 0.1)
				(type default)
			)
			(layer "F.Fab")
		)
		(fp_line
			(start 0.32512 -0.175006)
			(end 0.32512 0.175006)
			(stroke
				(width 0.1)
				(type default)
			)
			(layer "F.Fab")
		)
		(fp_line
			(start 0.32512 0.175006)
			(end -0.32512 0.175006)
			(stroke
				(width 0.1)
				(type default)
			)
			(layer "F.Fab")
		)
		(pad "1" smd rect
			(at -0.2667 0)
			(size 0.3048 0.381)
			(layers "F.Cu" "F.Mask" "F.Paste")
			(net "CLK_100M_RETIMER_CPU0_P1_R_DN")
		)
		(pad "2" smd rect
			(at 0.2667 0 180)
			(size 0.3048 0.381)
			(layers "F.Cu" "F.Mask" "F.Paste")
			(net "CLK_100M_RETIMER_CPU0_P1_DN")
		)
	)
	(footprint ""
		(layer "F.Cu")
		(at 282.397962 -351.927922)
		(property "Reference" "PR106"
			(at 0 0 0)
			(layer "F.SilkS")
			(hide yes)
			(effects
				(font
					(size 1.27 1.27)
				)
			)
		)
		(property "Value" ""
			(at 0 0 0)
			(layer "F.Fab")
			(effects
				(font
					(size 1.27 1.27)
				)
			)
		)
		(duplicate_pad_numbers_are_jumpers no)
		(fp_line
			(start -0.7874 -0.4064)
			(end 0.7874 -0.4064)
			(stroke
				(width 0.1524)
				(type default)
			)
			(layer "F.SilkS")
		)
		(fp_line
			(start -0.7874 0.4064)
			(end -0.7874 -0.4064)
			(stroke
				(width 0.1524)
				(type default)
			)
			(layer "F.SilkS")
		)
		(fp_line
			(start 0.7874 -0.4064)
			(end 0.7874 0.4064)
			(stroke
				(width 0.1524)
				(type default)
			)
			(layer "F.SilkS")
		)
		(fp_line
			(start 0.7874 0.4064)
			(end -0.7874 0.4064)
			(stroke
				(width 0.1524)
				(type default)
			)
			(layer "F.SilkS")
		)
		(fp_line
			(start -0.67945 -0.305054)
			(end -0.12065 -0.305054)
			(stroke
				(width 0.1)
				(type default)
			)
			(layer "F.Fab")
		)
		(fp_line
			(start -0.67945 0.3048)
			(end -0.67945 -0.305054)
			(stroke
				(width 0.1)
				(type default)
			)
			(layer "F.Fab")
		)
		(fp_line
			(start -0.12065 -0.305054)
			(end -0.12065 -0.2794)
			(stroke
				(width 0.1)
				(type default)
			)
			(layer "F.Fab")
		)
		(fp_line
			(start -0.12065 -0.2794)
			(end 0.12065 -0.2794)
			(stroke
				(width 0.1)
				(type default)
			)
			(layer "F.Fab")
		)
		(fp_line
			(start -0.12065 0.2794)
			(end -0.12065 0.3048)
			(stroke
				(width 0.1)
				(type default)
			)
			(layer "F.Fab")
		)
		(fp_line
			(start -0.12065 0.3048)
			(end -0.67945 0.3048)
			(stroke
				(width 0.1)
				(type default)
			)
			(layer "F.Fab")
		)
		(fp_line
			(start 0.120396 0.2794)
			(end -0.12065 0.2794)
			(stroke
				(width 0.1)
				(type default)
			)
			(layer "F.Fab")
		)
		(fp_line
			(start 0.120396 0.3048)
			(end 0.120396 0.2794)
			(stroke
				(width 0.1)
				(type default)
			)
			(layer "F.Fab")
		)
		(fp_line
			(start 0.12065 -0.3048)
			(end 0.67945 -0.3048)
			(stroke
				(width 0.1)
				(type default)
			)
			(layer "F.Fab")
		)
		(fp_line
			(start 0.12065 -0.2794)
			(end 0.12065 -0.3048)
			(stroke
				(width 0.1)
				(type default)
			)
			(layer "F.Fab")
		)
		(fp_line
			(start 0.67945 -0.3048)
			(end 0.67945 0.3048)
			(stroke
				(width 0.1)
				(type default)
			)
			(layer "F.Fab")
		)
		(fp_line
			(start 0.67945 0.3048)
			(end 0.120396 0.3048)
			(stroke
				(width 0.1)
				(type default)
			)
			(layer "F.Fab")
		)
		(pad "1" smd circle
			(at -0.40005 0)
			(size 0 0)
			(layers "F.Cu" "F.Mask" "F.Paste")
			(net "PVDDIO_P0_LSET3")
		)
		(pad "2" smd circle
			(at 0.40005 0)
			(size 0 0)
			(layers "F.Cu" "F.Mask" "F.Paste")
			(net "GND")
		)
	)
	(footprint ""
		(layer "F.Cu")
		(at 45.932344 -420.513764)
		(property "Reference" "R1464"
			(at 0 0 0)
			(layer "F.SilkS")
			(hide yes)
			(effects
				(font
					(size 1.27 1.27)
				)
			)
		)
		(property "Value" ""
			(at 0 0 0)
			(layer "F.Fab")
			(effects
				(font
					(size 1.27 1.27)
				)
			)
		)
		(duplicate_pad_numbers_are_jumpers no)
		(fp_line
			(start -0.32512 -0.175006)
			(end 0.32512 -0.175006)
			(stroke
				(width 0.1)
				(type default)
			)
			(layer "F.Fab")
		)
		(fp_line
			(start -0.32512 0.175006)
			(end -0.32512 -0.175006)
			(stroke
				(width 0.1)
				(type default)
			)
			(layer "F.Fab")
		)
		(fp_line
			(start 0.32512 -0.175006)
			(end 0.32512 0.175006)
			(stroke
				(width 0.1)
				(type default)
			)
			(layer "F.Fab")
		)
		(fp_line
			(start 0.32512 0.175006)
			(end -0.32512 0.175006)
			(stroke
				(width 0.1)
				(type default)
			)
			(layer "F.Fab")
		)
		(pad "1" smd rect
			(at -0.2667 0)
			(size 0.3048 0.381)
			(layers "F.Cu" "F.Mask" "F.Paste")
			(net "P1V8_CPU1_RT_1D")
		)
		(pad "2" smd rect
			(at 0.2667 0 180)
			(size 0.3048 0.381)
			(layers "F.Cu" "F.Mask" "F.Paste")
			(net "JTAG_TDI_RT_CPU1_P0")
		)
	)
)
